(kicad_pcb
	(version 20221018)
	(generator pcbnew)
	(general
    (thickness 1.7403)
  )
	(paper "A4")
	(title_block
    (title "Data Center RDIMM DDR4 Tester")
    (date "2024-09-30")
    (rev "1.2.4")
		(comment 9 "footprints 293-301 of 690")
	)
	(layers
    (0 "F.Cu" signal)
    (1 "In1.Cu" power)
    (2 "In2.Cu" signal)
    (3 "In3.Cu" power)
    (4 "In4.Cu" power)
    (5 "In5.Cu" signal)
    (6 "In6.Cu" power)
    (7 "In7.Cu" signal)
    (8 "In8.Cu" power)
    (9 "In9.Cu" signal)
    (10 "In10.Cu" power)
    (31 "B.Cu" signal)
    (32 "B.Adhes" user "B.Adhesive")
    (33 "F.Adhes" user "F.Adhesive")
    (34 "B.Paste" user)
    (35 "F.Paste" user)
    (36 "B.SilkS" user "B.Silkscreen")
    (37 "F.SilkS" user "F.Silkscreen")
    (38 "B.Mask" user)
    (39 "F.Mask" user)
    (40 "Dwgs.User" user "User.Drawings")
    (41 "Cmts.User" user "User.Comments")
    (42 "Eco1.User" user "User.Eco1")
    (43 "Eco2.User" user "User.Eco2")
    (44 "Edge.Cuts" user)
    (45 "Margin" user)
    (46 "B.CrtYd" user "B.Courtyard")
    (47 "F.CrtYd" user "F.Courtyard")
    (48 "B.Fab" user)
    (49 "F.Fab" user)
  )
	(footprint "data-center-rdimm-ddr4-tester-footprints:SC70-3" (layer "F.Cu")
    (at 221.8 122.7 180)
    (property "Author" "Antmicro")
    (property "License" "Apache-2.0")
    (property "MPN" "BSS138PW")
    (property "Manufacturer" "Nexperia")
    (property "Sheetfile" "supply.kicad_sch")
    (property "Sheetname" "Supply")
    (property "ki_description" "60 V, 320 mA N-channel enhancement mode Trench MOSFET, SC-70-3 aka SOT-323 package")
    (property "ki_keywords" "n-channel enhancement mosfet sc70 sc-70 sot-323 sot323")
    (attr smd)
    (fp_text reference "Q12" (at 1.04 1.27 180) (layer "F.SilkS")
        (effects (font (size 0.7 0.7) (thickness 0.15)) (justify left bottom))
    )
    (fp_text value "BSS138PW" (at 0 2.3 180) (layer "F.Fab") hide
        (effects (font (size 0.7 0.7) (thickness 0.15)) (justify left bottom))
    )
    (fp_text user "License: Apache-2.0" (at -1.45 6.782 180) (layer "F.Fab") hide
        (effects (font (size 0.7 0.7) (thickness 0.15)) (justify left bottom))
    )
    (fp_text user "Author: Antmicro" (at -1.45 5.782 180) (layer "F.Fab") hide
        (effects (font (size 0.7 0.7) (thickness 0.15)) (justify left bottom))
    )
    (fp_text user "${REFERENCE}" (at -1.45 4.783 180) (layer "F.Fab") hide
        (effects (font (size 0.7 0.7) (thickness 0.15)) (justify left bottom))
    )
    (fp_line (start -0.3 -1) (end 0.627 -0.999)
      (stroke (width 0.15) (type solid)) (layer "F.SilkS"))
    (fp_line (start -0.3 1) (end 0.627 1.001)
      (stroke (width 0.15) (type solid)) (layer "F.SilkS"))
    (fp_line (start 0.627 -0.6) (end 0.627 -0.999)
      (stroke (width 0.15) (type solid)) (layer "F.SilkS"))
    (fp_line (start 0.627 0.6) (end 0.627 1.001)
      (stroke (width 0.15) (type solid)) (layer "F.SilkS"))
    (fp_rect (start 1.4 1.3) (end -1.4 -1.3)
      (stroke (width 0.05) (type solid)) (fill none) (layer "F.CrtYd"))
    (fp_rect (start -0.623 -0.999) (end 0.627 1.001)
      (stroke (width 0.15) (type solid)) (fill none) (layer "F.Fab"))
    (pad "1" smd rect (at -0.95 -0.65 270) (size 0.6 0.8) (layers "F.Cu" "F.Paste" "F.Mask")
      (net 584 "Net-(Q12-G)") (pinfunction "G") (pintype "bidirectional"))
    (pad "2" smd rect (at -0.95 0.65 270) (size 0.6 0.8) (layers "F.Cu" "F.Paste" "F.Mask")
      (net 9 "GND") (pinfunction "S") (pintype "bidirectional"))
    (pad "3" smd rect (at 0.95 0 270) (size 0.6 0.8) (layers "F.Cu" "F.Paste" "F.Mask")
      (net 167 "/Supply/SYS_EN") (pinfunction "D") (pintype "bidirectional"))
  )
	(footprint "data-center-rdimm-ddr4-tester-footprints:R_0201" (layer "F.Cu")
    (at 161.825 104.29 90)
    (descr "Resistor SMD 0201")
    (tags "resistor SMD 0201")
    (property "Author" "Antmicro")
    (property "License" "Apache-2.0")
    (property "MPN" "CR0201-FX-0R00GLF")
    (property "Manufacturer" "Bourns")
    (property "Sheetfile" "ethernet.kicad_sch")
    (property "Sheetname" "Ethernet")
    (property "Tolerance" "1%")
    (property "Val" "0R")
    (property "ki_description" "0R resistor in 0201 package with 1% tolerance")
    (attr smd)
    (fp_text reference "R104" (at 0.59 0.575 90) (layer "F.SilkS")
        (effects (font (size 0.7 0.7) (thickness 0.15)) (justify left bottom))
    )
    (fp_text value "R_0R_0201" (at 0 1.25 90) (layer "F.Fab") hide
        (effects (font (size 0.7 0.7) (thickness 0.15)) (justify left bottom))
    )
    (fp_text user "${REFERENCE}" (at -0.71 3.25 90) (layer "F.Fab") hide
        (effects (font (size 0.7 0.7) (thickness 0.15)) (justify left bottom))
    )
    (fp_text user "Author: Antmicro" (at -0.71 5.25 90) (layer "F.Fab") hide
        (effects (font (size 0.7 0.7) (thickness 0.15)) (justify left bottom))
    )
    (fp_text user "License: Apache-2.0" (at -0.71 4.25 90) (layer "F.Fab") hide
        (effects (font (size 0.7 0.7) (thickness 0.15)) (justify left bottom))
    )
    (fp_rect (start -0.71 -0.36) (end 0.71 0.36)
      (stroke (width 0.05) (type solid)) (fill none) (layer "F.CrtYd"))
    (fp_rect (start -0.3 -0.15) (end 0.298 0.148)
      (stroke (width 0.15) (type solid)) (fill none) (layer "F.Fab"))
    (pad "" smd roundrect (at -0.346 0 90) (size 0.318 0.36) (layers "F.Paste") (roundrect_rratio 0.25))
    (pad "" smd roundrect (at 0.344 0 90) (size 0.318 0.36) (layers "F.Paste") (roundrect_rratio 0.25))
    (pad "1" smd roundrect (at -0.32 0 90) (size 0.46 0.4) (layers "F.Cu" "F.Mask") (roundrect_rratio 0.25)
      (net 831 "/Ethernet/ETH4_BP_N") (pintype "passive"))
    (pad "2" smd roundrect (at 0.32 0 90) (size 0.46 0.4) (layers "F.Cu" "F.Mask") (roundrect_rratio 0.25)
      (net 175 "/Ethernet/ETH4_N") (pintype "passive"))
  )
	(footprint "data-center-rdimm-ddr4-tester-footprints:C_0402_1005Metric" (layer "F.Cu")
    (at 254.71 96.955 180)
    (descr "Capacitor SMD 0402")
    (tags "capacitor SMD 0402")
    (property "Author" "Antmicro")
    (property "Dielectric" "X5R")
    (property "License" "Apache-2.0")
    (property "MPN" "GRM155R61H104KE14D")
    (property "Manufacturer" "Murata")
    (property "Sheetfile" "fmc_hpc.kicad_sch")
    (property "Sheetname" "FMC HPC")
    (property "Val" "100n")
    (property "Voltage" "50V")
    (property "ki_description" " ")
    (attr smd)
    (fp_text reference "C262" (at 3.64 -0.365 180) (layer "F.SilkS")
        (effects (font (size 0.7 0.7) (thickness 0.15)) (justify left bottom))
    )
    (fp_text value "C_100n_0402" (at 0 1.4 180) (layer "F.Fab") hide
        (effects (font (size 0.7 0.7) (thickness 0.15)) (justify left bottom))
    )
    (fp_text user "Author: Antmicro" (at -0.932 4.17 180) (layer "F.Fab") hide
        (effects (font (size 0.7 0.7) (thickness 0.15)) (justify left bottom))
    )
    (fp_text user "License: Apache-2.0" (at -0.932 5.17 180) (layer "F.Fab") hide
        (effects (font (size 0.7 0.7) (thickness 0.15)) (justify left bottom))
    )
    (fp_text user "${REFERENCE}" (at -0.932 3.168 180) (layer "F.Fab") hide
        (effects (font (size 0.7 0.7) (thickness 0.15)) (justify left bottom))
    )
    (fp_rect (start -0.94 -0.47) (end 0.94 0.47)
      (stroke (width 0.05) (type solid)) (fill none) (layer "F.CrtYd"))
    (fp_rect (start -0.499 -0.249) (end 0.499 0.249)
      (stroke (width 0.15) (type solid)) (fill none) (layer "F.Fab"))
    (pad "1" smd roundrect (at -0.484 0 180) (size 0.59 0.64) (layers "F.Cu" "F.Paste" "F.Mask") (roundrect_rratio 0.25)
      (net 421 "/FMC HPC/GTX_TX1_C_N") (pintype "passive"))
    (pad "2" smd roundrect (at 0.484 0 180) (size 0.59 0.64) (layers "F.Cu" "F.Paste" "F.Mask") (roundrect_rratio 0.25)
      (net 429 "GTX_TX1_N") (pintype "passive"))
  )
	(footprint "data-center-rdimm-ddr4-tester-footprints:R_0201" (layer "F.Cu")
    (at 151.35 106.775 -90)
    (descr "Resistor SMD 0201")
    (tags "resistor SMD 0201")
    (property "Author" "Antmicro")
    (property "License" "Apache-2.0")
    (property "MPN" "CR0201-FX-0R00GLF")
    (property "Manufacturer" "Bourns")
    (property "Sheetfile" "ethernet.kicad_sch")
    (property "Sheetname" "Ethernet")
    (property "Tolerance" "1%")
    (property "Val" "0R")
    (property "ki_description" "0R resistor in 0201 package with 1% tolerance")
    (attr smd)
    (fp_text reference "R222" (at -3.385 -0.4 90) (layer "F.SilkS")
        (effects (font (size 0.7 0.7) (thickness 0.15)) (justify right bottom))
    )
    (fp_text value "R_0R_0201" (at 0 1.25 90) (layer "F.Fab") hide
        (effects (font (size 0.7 0.7) (thickness 0.15)) (justify right bottom))
    )
    (fp_text user "${REFERENCE}" (at -0.71 3.25 90) (layer "F.Fab") hide
        (effects (font (size 0.7 0.7) (thickness 0.15)) (justify right bottom))
    )
    (fp_text user "Author: Antmicro" (at -0.71 5.25 90) (layer "F.Fab") hide
        (effects (font (size 0.7 0.7) (thickness 0.15)) (justify right bottom))
    )
    (fp_text user "License: Apache-2.0" (at -0.71 4.25 90) (layer "F.Fab") hide
        (effects (font (size 0.7 0.7) (thickness 0.15)) (justify right bottom))
    )
    (fp_rect (start -0.71 -0.36) (end 0.71 0.36)
      (stroke (width 0.05) (type solid)) (fill none) (layer "F.CrtYd"))
    (fp_rect (start -0.3 -0.15) (end 0.298 0.148)
      (stroke (width 0.15) (type solid)) (fill none) (layer "F.Fab"))
    (pad "" smd roundrect (at -0.346 0 270) (size 0.318 0.36) (layers "F.Paste") (roundrect_rratio 0.25))
    (pad "" smd roundrect (at 0.344 0 270) (size 0.318 0.36) (layers "F.Paste") (roundrect_rratio 0.25))
    (pad "1" smd roundrect (at -0.32 0 270) (size 0.46 0.4) (layers "F.Cu" "F.Mask") (roundrect_rratio 0.25)
      (net 17 "LED_SPD") (pintype "passive"))
    (pad "2" smd roundrect (at 0.32 0 270) (size 0.46 0.4) (layers "F.Cu" "F.Mask") (roundrect_rratio 0.25)
      (net 546 "INT_LED_SPD") (pintype "passive"))
  )
	(footprint "data-center-rdimm-ddr4-tester-footprints:LED_RGY_1.6x1.6mm_APTF1616" (layer "F.Cu")
    (at 251.666 76.898 180)
    (descr "1.6 x 1.6 mm Full-Color Surface Mount LED")
    (tags "LED")
    (property "Author" "Antmicro")
    (property "Description" "Standard LEDs - SMD RGY 1616 SMD")
    (property "License" "Apache-2.0")
    (property "MPN" "APTF1616SURKCGKSYKC")
    (property "Manufacturer" "Kingbright")
    (property "Sheetfile" "interfaces.kicad_sch")
    (property "Sheetname" "Interfaces")
    (property "ki_description" "Standard LEDs - SMD RGY 1616 SMD")
    (attr smd)
    (fp_text reference "D17" (at 1.8 1.2) (layer "F.SilkS")
        (effects (font (size 0.7 0.7) (thickness 0.15)) (justify left bottom))
    )
    (fp_text value "LED_RGY_0606_APTF1616SURKCGKSYKC" (at 0 2) (layer "F.Fab")
        (effects (font (size 0.7 0.7) (thickness 0.15)) (justify right bottom))
    )
    (fp_text user "License: Apache-2.0" (at -1.3 5.698) (layer "F.Fab") hide
        (effects (font (size 0.7 0.7) (thickness 0.15)) (justify right bottom))
    )
    (fp_text user "${REFERENCE}" (at -1.3 3.297) (layer "F.Fab") hide
        (effects (font (size 0.7 0.7) (thickness 0.15)) (justify right bottom))
    )
    (fp_text user "Author: Antmicro" (at -1.3 4.496) (layer "F.Fab") hide
        (effects (font (size 0.7 0.7) (thickness 0.15)) (justify right bottom))
    )
    (fp_line (start -0.8 -0.15) (end -0.801 0.15)
      (stroke (width 0.15) (type solid)) (layer "F.SilkS"))
    (fp_line (start -0.35 0.8) (end 0.35 0.8)
      (stroke (width 0.15) (type solid)) (layer "F.SilkS"))
    (fp_line (start 0.35 -0.802) (end -0.35 -0.802)
      (stroke (width 0.15) (type solid)) (layer "F.SilkS"))
    (fp_line (start 0.8 0.148) (end 0.8 -0.102)
      (stroke (width 0.15) (type solid)) (layer "F.SilkS"))
    (fp_circle (center -1.05 -0.95) (end -1.101 -0.999)
      (stroke (width 0.15) (type solid)) (fill solid) (layer "F.SilkS"))
    (fp_rect (start 1.3 1.1) (end -1.3 -1.1)
      (stroke (width 0.05) (type solid)) (fill none) (layer "F.CrtYd"))
    (fp_rect (start -0.801 -0.802) (end 0.8 0.801)
      (stroke (width 0.15) (type solid)) (fill none) (layer "F.Fab"))
    (pad "1" smd rect (at -0.874 -0.499 90) (size 0.5 0.85) (layers "F.Cu" "F.Paste" "F.Mask")
      (net 143 "3V3_SYS") (pinfunction "A") (pintype "passive"))
    (pad "2" smd rect (at 0.874 -0.499 90) (size 0.5 0.85) (layers "F.Cu" "F.Paste" "F.Mask")
      (net 101 "Net-(D17-C_{R})") (pinfunction "C_{R}") (pintype "passive"))
    (pad "3" smd rect (at 0.874 0.498 90) (size 0.5 0.85) (layers "F.Cu" "F.Paste" "F.Mask")
      (net 102 "Net-(D17-C_{G})") (pinfunction "C_{G}") (pintype "passive"))
    (pad "4" smd rect (at -0.874 0.498 90) (size 0.5 0.85) (layers "F.Cu" "F.Paste" "F.Mask")
      (net 106 "Net-(D17-C_{Y})") (pinfunction "C_{Y}") (pintype "passive"))
  )
	(footprint "data-center-rdimm-ddr4-tester-footprints:R_0201" (layer "F.Cu")
    (at 161.55 109.03 90)
    (descr "Resistor SMD 0201")
    (tags "resistor SMD 0201")
    (property "Author" "Antmicro")
    (property "License" "Apache-2.0")
    (property "MPN" "CR0201-FX-0R00GLF")
    (property "Manufacturer" "Bourns")
    (property "Sheetfile" "ethernet.kicad_sch")
    (property "Sheetname" "Ethernet")
    (property "Tolerance" "1%")
    (property "Val" "0R")
    (property "ki_description" "0R resistor in 0201 package with 1% tolerance")
    (attr smd)
    (fp_text reference "R110" (at -3.48 0.51 90) (layer "F.SilkS")
        (effects (font (size 0.7 0.7) (thickness 0.15)) (justify left bottom))
    )
    (fp_text value "R_0R_0201" (at 0 1.25 90) (layer "F.Fab") hide
        (effects (font (size 0.7 0.7) (thickness 0.15)) (justify left bottom))
    )
    (fp_text user "${REFERENCE}" (at -0.71 3.25 90) (layer "F.Fab") hide
        (effects (font (size 0.7 0.7) (thickness 0.15)) (justify left bottom))
    )
    (fp_text user "Author: Antmicro" (at -0.71 5.25 90) (layer "F.Fab") hide
        (effects (font (size 0.7 0.7) (thickness 0.15)) (justify left bottom))
    )
    (fp_text user "License: Apache-2.0" (at -0.71 4.25 90) (layer "F.Fab") hide
        (effects (font (size 0.7 0.7) (thickness 0.15)) (justify left bottom))
    )
    (fp_rect (start -0.71 -0.36) (end 0.71 0.36)
      (stroke (width 0.05) (type solid)) (fill none) (layer "F.CrtYd"))
    (fp_rect (start -0.3 -0.15) (end 0.298 0.148)
      (stroke (width 0.15) (type solid)) (fill none) (layer "F.Fab"))
    (pad "" smd roundrect (at -0.346 0 90) (size 0.318 0.36) (layers "F.Paste") (roundrect_rratio 0.25))
    (pad "" smd roundrect (at 0.344 0 90) (size 0.318 0.36) (layers "F.Paste") (roundrect_rratio 0.25))
    (pad "1" smd roundrect (at -0.32 0 90) (size 0.46 0.4) (layers "F.Cu" "F.Mask") (roundrect_rratio 0.25)
      (net 558 "/Ethernet/INT_ETH3_N") (pintype "passive"))
    (pad "2" smd roundrect (at 0.32 0 90) (size 0.46 0.4) (layers "F.Cu" "F.Mask") (roundrect_rratio 0.25)
      (net 829 "/Ethernet/ETH3_BP_N") (pintype "passive"))
  )
	(footprint "data-center-rdimm-ddr4-tester-footprints:R_0402_1005Metric" (layer "F.Cu")
    (at 221.85 125.4)
    (descr "Resistor SMD 0402")
    (tags "resistor SMD 0402")
    (property "Author" "Antmicro")
    (property "License" "Apache-2.0")
    (property "MPN" "CR0402-FX-4701GLF")
    (property "Manufacturer" "Bourns")
    (property "Sheetfile" "interfaces.kicad_sch")
    (property "Sheetname" "Interfaces")
    (property "Tolerance" "1%")
    (property "Val" "4k7")
    (property "ki_description" "4k7 resistor in 0402 package with 1% tolerance")
    (attr smd)
    (fp_text reference "R190" (at -1.41 -0.52) (layer "F.SilkS")
        (effects (font (size 0.7 0.7) (thickness 0.15)) (justify left bottom))
    )
    (fp_text value "R_4k7_0402" (at 0 1.4) (layer "F.Fab") hide
        (effects (font (size 0.7 0.7) (thickness 0.15)) (justify left bottom))
    )
    (fp_text user "Author: Antmicro" (at -0.95 4.169) (layer "F.Fab") hide
        (effects (font (size 0.7 0.7) (thickness 0.15)) (justify left bottom))
    )
    (fp_text user "License: Apache-2.0" (at -0.95 5.169) (layer "F.Fab") hide
        (effects (font (size 0.7 0.7) (thickness 0.15)) (justify left bottom))
    )
    (fp_text user "${REFERENCE}" (at -0.95 3.168) (layer "F.Fab") hide
        (effects (font (size 0.7 0.7) (thickness 0.15)) (justify left bottom))
    )
    (fp_rect (start -0.93 -0.47) (end 0.93 0.47)
      (stroke (width 0.05) (type solid)) (fill none) (layer "F.CrtYd"))
    (fp_rect (start -0.5 -0.25) (end 0.5 0.25)
      (stroke (width 0.15) (type solid)) (fill none) (layer "F.Fab"))
    (pad "1" smd roundrect (at -0.485 0) (size 0.59 0.64) (layers "F.Cu" "F.Paste" "F.Mask") (roundrect_rratio 0.25)
      (net 143 "3V3_SYS") (pintype "passive"))
    (pad "2" smd roundrect (at 0.485 0) (size 0.59 0.64) (layers "F.Cu" "F.Paste" "F.Mask") (roundrect_rratio 0.25)
      (net 149 "HOT_SWAP_BUTTON") (pintype "passive"))
  )
	(footprint "data-center-rdimm-ddr4-tester-footprints:NetTie-2_SMD_Pad0.127mm" (layer "F.Cu")
    (at 119.65 82.633 90)
    (descr "Net tie, 2 pin, 0.127mm  SMD pads")
    (tags "net tie")
    (property "Author" "Antmicro")
    (property "License" "Apache-2.0")
    (property "MPN" "")
    (property "Manufacturer" "")
    (property "Sheetfile" "supply.kicad_sch")
    (property "Sheetname" "Supply")
    (property "ki_description" "Net tie, 2 pins")
    (property "ki_keywords" "net tie short")
    (attr through_hole exclude_from_pos_files)
    (net_tie_pad_groups "1, 2")
    (fp_text reference "NT4" (at -0.128 -1.345 90) (layer "F.SilkS") hide
        (effects (font (size 0.7 0.7) (thickness 0.15)) (justify left bottom))
    )
    (fp_text value "Net-Tie_2" (at 0 1.199 90) (layer "F.Fab") hide
        (effects (font (size 0.7 0.7) (thickness 0.15)) (justify left bottom))
    )
    (fp_text user "Author: Antmicro" (at -0.128 4.4 90) (layer "F.Fab") hide
        (effects (font (size 0.7 0.7) (thickness 0.15)) (justify left bottom))
    )
    (fp_text user "${REFERENCE}" (at -0.128 3.2 90) (layer "F.Fab") hide
        (effects (font (size 0.7 0.7) (thickness 0.15)) (justify left bottom))
    )
    (fp_text user "License: Apache-2.0" (at -0.128 5.6 90) (layer "F.Fab") hide
        (effects (font (size 0.7 0.7) (thickness 0.15)) (justify left bottom))
    )
    (fp_poly
      (pts
        (xy -0.0635 -0.0635)
        (xy 0.0625 -0.0635)
        (xy 0.0625 0.0635)
        (xy -0.0635 0.0635)
      )

      (stroke (width 0) (type solid)) (fill solid) (layer "F.Cu"))
    (pad "1" smd roundrect (at -0.127 0 270) (size 0.127 0.127) (layers "F.Cu") (roundrect_rratio 0.5)
      (chamfer_ratio 0) (chamfer top_left bottom_left)
      (net 835 "/Supply/VDDQ_SEN_-") (pinfunction "1") (pintype "passive"))
    (pad "2" smd roundrect (at 0.126 0 90) (size 0.127 0.127) (layers "F.Cu") (roundrect_rratio 0.5)
      (chamfer_ratio 0) (chamfer top_left bottom_left)
      (net 77 "VDDQ") (pinfunction "2") (pintype "passive"))
  )
	(footprint "data-center-rdimm-ddr4-tester-footprints:NetTie-2_SMD_Pad0.127mm" (layer "F.Cu")
    (at 130.7 82.53 90)
    (descr "Net tie, 2 pin, 0.127mm  SMD pads")
    (tags "net tie")
    (property "Author" "Antmicro")
    (property "License" "Apache-2.0")
    (property "MPN" "")
    (property "Manufacturer" "")
    (property "Sheetfile" "supply.kicad_sch")
    (property "Sheetname" "Supply")
    (property "ki_description" "Net tie, 2 pins")
    (property "ki_keywords" "net tie short")
    (attr through_hole exclude_from_pos_files)
    (net_tie_pad_groups "1, 2")
    (fp_text reference "NT13" (at -0.128 -1.345 90) (layer "F.SilkS") hide
        (effects (font (size 0.7 0.7) (thickness 0.15)) (justify left bottom))
    )
    (fp_text value "Net-Tie_2" (at 0 1.199 90) (layer "F.Fab") hide
        (effects (font (size 0.7 0.7) (thickness 0.15)) (justify left bottom))
    )
    (fp_text user "Author: Antmicro" (at -0.128 4.4 90) (layer "F.Fab") hide
        (effects (font (size 0.7 0.7) (thickness 0.15)) (justify left bottom))
    )
    (fp_text user "License: Apache-2.0" (at -0.128 5.6 90) (layer "F.Fab") hide
        (effects (font (size 0.7 0.7) (thickness 0.15)) (justify left bottom))
    )
    (fp_text user "${REFERENCE}" (at -0.128 3.2 90) (layer "F.Fab") hide
        (effects (font (size 0.7 0.7) (thickness 0.15)) (justify left bottom))
    )
    (fp_poly
      (pts
        (xy -0.0635 -0.0635)
        (xy 0.0625 -0.0635)
        (xy 0.0625 0.0635)
        (xy -0.0635 0.0635)
      )

      (stroke (width 0) (type solid)) (fill solid) (layer "F.Cu"))
    (pad "1" smd roundrect (at -0.127 0 270) (size 0.127 0.127) (layers "F.Cu") (roundrect_rratio 0.5)
      (chamfer_ratio 0) (chamfer top_left bottom_left)
      (net 844 "/Supply/1V8_SEN_-") (pinfunction "1") (pintype "passive"))
    (pad "2" smd roundrect (at 0.126 0 90) (size 0.127 0.127) (layers "F.Cu") (roundrect_rratio 0.5)
      (chamfer_ratio 0) (chamfer top_left bottom_left)
      (net 144 "1V8_SYS") (pinfunction "2") (pintype "passive"))
  )
)
